(kicad_pcb
	(version 20241229)
	(generator "pcbnew")
	(generator_version "9.0")
	(general
		(thickness 1.61)
		(legacy_teardrops no)
	)
	(paper "A3")
	(title_block
		(title "RDIMM DDR5 Tester")
		(date "2026-05-21")
		(rev "2.2.0")
		(company "Antmicro")
		(comment 9 "footprints 142-144 of 796")
	)
	(layers
		(0 "F.Cu" signal)
		(4 "In1.Cu" power)
		(6 "In2.Cu" mixed)
		(8 "In3.Cu" power)
		(10 "In4.Cu" mixed)
		(12 "In5.Cu" power)
		(14 "In6.Cu" mixed)
		(16 "In7.Cu" power)
		(18 "In8.Cu" power)
		(20 "In9.Cu" mixed)
		(22 "In10.Cu" power)
		(2 "B.Cu" signal)
		(9 "F.Adhes" user "F.Adhesive")
		(11 "B.Adhes" user "B.Adhesive")
		(13 "F.Paste" user)
		(15 "B.Paste" user)
		(5 "F.SilkS" user "F.Silkscreen")
		(7 "B.SilkS" user "B.Silkscreen")
		(1 "F.Mask" user)
		(3 "B.Mask" user)
		(17 "Dwgs.User" user "User.Drawings")
		(19 "Cmts.User" user "User.Comments")
		(21 "Eco1.User" user "User.Eco1")
		(23 "Eco2.User" user "User.Eco2")
		(25 "Edge.Cuts" user)
		(27 "Margin" user)
		(31 "F.CrtYd" user "F.Courtyard")
		(29 "B.CrtYd" user "B.Courtyard")
		(35 "F.Fab" user)
		(33 "B.Fab" user)
	)
	(footprint "antmicro-footprints:SOT-23-5"
		(layer "F.Cu")
		(at 112.124499 139.549)
		(property "Reference" "U5"
			(at 0.4 2.7 0)
			(layer "F.SilkS")
			(effects
				(font
					(size 0.7 0.7)
					(thickness 0.15)
				)
				(justify left bottom)
			)
		)
		(property "Value" "NCP718BSN330T1G"
			(at 0.002 2.799 0)
			(layer "F.Fab")
			(effects
				(font
					(size 0.7 0.7)
					(thickness 0.15)
				)
				(justify left bottom)
			)
		)
		(property "Datasheet" "https://www.mouser.com/datasheet/2/308/NCP718_D-1224359.pdf"
			(at 0 0 0)
			(layer "F.Fab")
			(hide yes)
			(effects
				(font
					(size 1.27 1.27)
					(thickness 0.15)
				)
			)
		)
		(property "MPN" "NCP718BSN330T1G"
			(at 0 0 0)
			(unlocked yes)
			(layer "F.Fab")
			(hide yes)
			(effects
				(font
					(size 1 1)
					(thickness 0.15)
				)
			)
		)
		(property "Manufacturer" "ON Semiconductor"
			(at 0 0 0)
			(unlocked yes)
			(layer "F.Fab")
			(hide yes)
			(effects
				(font
					(size 1 1)
					(thickness 0.15)
				)
			)
		)
		(property "Author" "Antmicro"
			(at 0 0 0)
			(unlocked yes)
			(layer "F.Fab")
			(hide yes)
			(effects
				(font
					(size 1 1)
					(thickness 0.15)
				)
			)
		)
		(property "License" "Apache-2.0"
			(at 0 0 0)
			(unlocked yes)
			(layer "F.Fab")
			(hide yes)
			(effects
				(font
					(size 1 1)
					(thickness 0.15)
				)
			)
		)
		(sheetname "/Debug FTDI + VNA/")
		(sheetfile "debug-ftdi.kicad_sch")
		(attr smd)
		(fp_line
			(start -0.85 1.6)
			(end -0.85 1.301)
			(stroke
				(width 0.15)
				(type solid)
			)
			(layer "F.SilkS")
		)
		(fp_line
			(start -0.8 -1.6)
			(end -0.8 -1.3)
			(stroke
				(width 0.15)
				(type solid)
			)
			(layer "F.SilkS")
		)
		(fp_line
			(start -0.8 -1.6)
			(end -0.5 -1.6)
			(stroke
				(width 0.15)
				(type solid)
			)
			(layer "F.SilkS")
		)
		(fp_line
			(start -0.55 1.6)
			(end -0.85 1.6)
			(stroke
				(width 0.15)
				(type solid)
			)
			(layer "F.SilkS")
		)
		(fp_line
			(start 0.8 -1.6)
			(end 0.5 -1.6)
			(stroke
				(width 0.15)
				(type solid)
			)
			(layer "F.SilkS")
		)
		(fp_line
			(start 0.8 -1.3)
			(end 0.8 -1.6)
			(stroke
				(width 0.15)
				(type solid)
			)
			(layer "F.SilkS")
		)
		(fp_line
			(start 0.8 0.55)
			(end 0.8 -0.55)
			(stroke
				(width 0.15)
				(type solid)
			)
			(layer "F.SilkS")
		)
		(fp_line
			(start 0.8 1.3)
			(end 0.8 1.599)
			(stroke
				(width 0.15)
				(type solid)
			)
			(layer "F.SilkS")
		)
		(fp_line
			(start 0.8 1.599)
			(end 0.549 1.599)
			(stroke
				(width 0.15)
				(type solid)
			)
			(layer "F.SilkS")
		)
		(fp_circle
			(center -1.25 -1.5)
			(end -1.2 -1.5)
			(stroke
				(width 0.15)
				(type solid)
			)
			(fill yes)
			(layer "F.SilkS")
		)
		(fp_rect
			(start 1.9 -1.76)
			(end -1.9 1.75)
			(stroke
				(width 0.05)
				(type solid)
			)
			(fill no)
			(layer "F.CrtYd")
		)
		(fp_line
			(start -0.398 -1.526)
			(end -0.874 -1.05)
			(stroke
				(width 0.15)
				(type solid)
			)
			(layer "F.Fab")
		)
		(fp_rect
			(start 0.874 1.523)
			(end -0.873 -1.525)
			(stroke
				(width 0.15)
				(type solid)
			)
			(fill no)
			(layer "F.Fab")
		)
		(fp_text user "${REFERENCE}"
			(at -1.898 4.299 0)
			(layer "F.Fab")
			(effects
				(font
					(size 0.7 0.7)
					(thickness 0.15)
				)
				(justify left bottom)
			)
		)
		(fp_text user "Author: Antmicro"
			(at -1.898 5.499 0)
			(layer "F.Fab")
			(effects
				(font
					(size 0.7 0.7)
					(thickness 0.15)
				)
				(justify left bottom)
			)
		)
		(fp_text user "License: Apache-2.0"
			(at -1.898 6.7 0)
			(layer "F.Fab")
			(effects
				(font
					(size 0.7 0.7)
					(thickness 0.15)
				)
				(justify left bottom)
			)
		)
		(pad "1" smd rect
			(at -1.351 -0.951 270)
			(size 0.55 1)
			(layers "F.Cu" "F.Mask" "F.Paste")
			(net 2 "/Debug FTDI + VNA/VBUS")
			(pinfunction "VIN")
			(pintype "passive")
		)
		(pad "2" smd rect
			(at -1.351 0 270)
			(size 0.55 1)
			(layers "F.Cu" "F.Mask" "F.Paste")
			(net 1 "GND")
			(pinfunction "GND")
			(pintype "passive")
		)
		(pad "3" smd rect
			(at -1.351 0.949 270)
			(size 0.55 1)
			(layers "F.Cu" "F.Mask" "F.Paste")
			(net 2 "/Debug FTDI + VNA/VBUS")
			(pinfunction "EN")
			(pintype "passive")
		)
		(pad "4" smd rect
			(at 1.35 0.949 270)
			(size 0.55 1)
			(layers "F.Cu" "F.Mask" "F.Paste")
			(net 311 "unconnected-(U5-NC-Pad4)")
			(pinfunction "NC")
			(pintype "no_connect")
		)
		(pad "5" smd rect
			(at 1.35 -0.951 270)
			(size 0.55 1)
			(layers "F.Cu" "F.Mask" "F.Paste")
			(net 6 "/Debug FTDI + VNA/FTDI_3V3")
			(pinfunction "VOUT")
			(pintype "passive")
		)
	)
	(footprint "antmicro-footprints:Resonator_SMD_Abracon_ABM8G_3.2x2.5mm"
		(layer "F.Cu")
		(at 158.030003 155.609999 -135)
		(property "Reference" "Y4"
			(at 0.85 1.7 45)
			(layer "F.SilkS")
			(effects
				(font
					(size 0.7 0.7)
					(thickness 0.15)
				)
				(justify right bottom)
			)
		)
		(property "Value" "Resonator_114.285MHZ_ABM8"
			(at -1.75 2.548 45)
			(layer "F.Fab")
			(effects
				(font
					(size 0.7 0.7)
					(thickness 0.15)
				)
				(justify right bottom)
			)
		)
		(property "Datasheet" "https://abracon.com/Resonators/ABM8-166.pdf"
			(at 0 0 225)
			(layer "F.Fab")
			(hide yes)
			(effects
				(font
					(size 1.27 1.27)
					(thickness 0.15)
				)
			)
		)
		(property "MPN" "ABM8-166-114.285MHZ-T2"
			(at 0 0 225)
			(unlocked yes)
			(layer "F.Fab")
			(hide yes)
			(effects
				(font
					(size 1 1)
					(thickness 0.15)
				)
			)
		)
		(property "Manufacturer" "Abracon"
			(at 0 0 225)
			(unlocked yes)
			(layer "F.Fab")
			(hide yes)
			(effects
				(font
					(size 1 1)
					(thickness 0.15)
				)
			)
		)
		(property "Author" "Antmicro"
			(at 0 0 225)
			(unlocked yes)
			(layer "F.Fab")
			(hide yes)
			(effects
				(font
					(size 1 1)
					(thickness 0.15)
				)
			)
		)
		(property "License" "Apache-2.0"
			(at 0 0 225)
			(unlocked yes)
			(layer "F.Fab")
			(hide yes)
			(effects
				(font
					(size 1 1)
					(thickness 0.15)
				)
			)
		)
		(property "Val" "114.285 MHz"
			(at 0 0 225)
			(unlocked yes)
			(layer "F.Fab")
			(hide yes)
			(effects
				(font
					(size 1 1)
					(thickness 0.15)
				)
			)
		)
		(sheetname "/FPGA MGT Interface/")
		(sheetfile "fpga-mgt.kicad_sch")
		(attr smd)
		(fp_line
			(start 1.6 0.3)
			(end 1.6 -0.2)
			(stroke
				(width 0.15)
				(type solid)
			)
			(layer "F.SilkS")
		)
		(fp_line
			(start -0.35 1.25)
			(end 0.450001 1.25)
			(stroke
				(width 0.15)
				(type solid)
			)
			(layer "F.SilkS")
		)
		(fp_line
			(start -1.6 0.3)
			(end -1.6 -0.2)
			(stroke
				(width 0.15)
				(type solid)
			)
			(layer "F.SilkS")
		)
		(fp_line
			(start -0.35 -1.25)
			(end 0.450001 -1.25)
			(stroke
				(width 0.15)
				(type solid)
			)
			(layer "F.SilkS")
		)
		(fp_circle
			(center -1.75 1.5)
			(end -1.7 1.5)
			(stroke
				(width 0.15)
				(type solid)
			)
			(fill no)
			(layer "F.SilkS")
		)
		(fp_poly
			(pts
				(xy -1.907 -1.55) (xy 2.006 -1.55) (xy 2.006 1.649) (xy -1.907001 1.649)
			)
			(stroke
				(width 0.05)
				(type solid)
			)
			(fill no)
			(layer "F.CrtYd")
		)
		(fp_text user "Author: Antmicro"
			(at -1.75 5 225)
			(layer "F.Fab")
			(effects
				(font
					(size 0.7 0.7)
					(thickness 0.15)
				)
				(justify left bottom)
			)
		)
		(fp_text user "License: Apache-2.0"
			(at -1.75 6.5 225)
			(layer "F.Fab")
			(effects
				(font
					(size 0.7 0.7)
					(thickness 0.15)
				)
				(justify left bottom)
			)
		)
		(fp_text user "${REFERENCE}"
			(at -1.749999 3.75 225)
			(layer "F.Fab")
			(effects
				(font
					(size 0.7 0.7)
					(thickness 0.15)
				)
				(justify left bottom)
			)
		)
		(pad "1" smd roundrect
			(at -1.101 0.949 225)
			(size 1.3 1.1)
			(layers "F.Cu" "F.Mask" "F.Paste")
			(roundrect_rratio 0)
			(chamfer_ratio 0.2)
			(chamfer bottom_left)
			(net 764 "/FPGA MGT Interface/XA")
			(pintype "passive")
		)
		(pad "2" smd rect
			(at 1.199 0.949 225)
			(size 1.3 1.1)
			(layers "F.Cu" "F.Mask" "F.Paste")
			(net 1 "GND")
			(pinfunction "SH")
			(pintype "passive")
		)
		(pad "3" smd rect
			(at 1.199 -0.85 225)
			(size 1.3 1.1)
			(layers "F.Cu" "F.Mask" "F.Paste")
			(net 765 "/FPGA MGT Interface/XB")
			(pintype "passive")
		)
		(pad "4" smd rect
			(at -1.101 -0.85 225)
			(size 1.3 1.1)
			(layers "F.Cu" "F.Mask" "F.Paste")
			(net 1 "GND")
			(pinfunction "SH")
			(pintype "passive")
		)
	)
	(footprint "antmicro-footprints:LED_0603_1608Metric_G"
		(layer "F.Cu")
		(at 108.005 102.225 90)
		(descr "LED SMD 0603 Green")
		(tags "LED SMD 0603 Green")
		(property "Reference" "D6"
			(at -2.575 -0.305 90)
			(layer "F.SilkS")
			(hide yes)
			(effects
				(font
					(size 0.7 0.7)
					(thickness 0.15)
				)
				(justify left bottom)
			)
		)
		(property "Value" "LED_G_0603_KP-1608CGCK"
			(at -0.001 1.599 90)
			(layer "F.Fab")
			(effects
				(font
					(size 0.7 0.7)
					(thickness 0.15)
				)
				(justify left bottom)
			)
		)
		(property "Datasheet" "http://www.kingbright.com/attachments/file/psearch//000/00/00/KP-1608CGCK(Ver.23B).pdf"
			(at 0 0 90)
			(layer "F.Fab")
			(hide yes)
			(effects
				(font
					(size 1.27 1.27)
					(thickness 0.15)
				)
			)
		)
		(property "MPN" "KP-1608CGCK"
			(at 0 0 90)
			(unlocked yes)
			(layer "F.Fab")
			(hide yes)
			(effects
				(font
					(size 1 1)
					(thickness 0.15)
				)
			)
		)
		(property "Manufacturer" "Kingbright"
			(at 0 0 90)
			(unlocked yes)
			(layer "F.Fab")
			(hide yes)
			(effects
				(font
					(size 1 1)
					(thickness 0.15)
				)
			)
		)
		(property "Author" "Antmicro"
			(at 0 0 90)
			(unlocked yes)
			(layer "F.Fab")
			(hide yes)
			(effects
				(font
					(size 1 1)
					(thickness 0.15)
				)
			)
		)
		(property "License" "Apache-2.0"
			(at 0 0 90)
			(unlocked yes)
			(layer "F.Fab")
			(hide yes)
			(effects
				(font
					(size 1 1)
					(thickness 0.15)
				)
			)
		)
		(property "Color" "Green"
			(at 0 0 90)
			(unlocked yes)
			(layer "F.Fab")
			(hide yes)
			(effects
				(font
					(size 1 1)
					(thickness 0.15)
				)
			)
		)
		(sheetname "/FPGA banks HD/")
		(sheetfile "fpga-hd-banks.kicad_sch")
		(attr smd)
		(fp_line
			(start 0.22 -0.35)
			(end -0.22 -0.35)
			(stroke
				(width 0.15)
				(type solid)
			)
			(layer "F.SilkS")
		)
		(fp_line
			(start -1.18 -0.319)
			(end -1.18 0.321)
			(stroke
				(width 0.15)
				(type solid)
			)
			(layer "F.SilkS")
		)
		(fp_line
			(start 0.105328 0.001008)
			(end 0.24 0.001)
			(stroke
				(width 0.1)
				(type solid)
			)
			(layer "F.SilkS")
		)
		(fp_line
			(start -0.094672 0.001008)
			(end 0.105328 -0.198992)
			(stroke
				(width 0.1)
				(type solid)
			)
			(layer "F.SilkS")
		)
		(fp_line
			(start -0.094672 0.001008)
			(end -0.24 0.001008)
			(stroke
				(width 0.1)
				(type solid)
			)
			(layer "F.SilkS")
		)
		(fp_line
			(start 0.105328 0.201008)
			(end 0.105328 -0.198992)
			(stroke
				(width 0.1)
				(type solid)
			)
			(layer "F.SilkS")
		)
		(fp_line
			(start 0.105328 0.201008)
			(end -0.094672 0.001008)
			(stroke
				(width 0.1)
				(type solid)
			)
			(layer "F.SilkS")
		)
		(fp_line
			(start -0.094672 0.201008)
			(end -0.094672 -0.198992)
			(stroke
				(width 0.1)
				(type solid)
			)
			(layer "F.SilkS")
		)
		(fp_line
			(start 0.22 0.35)
			(end -0.22 0.35)
			(stroke
				(width 0.15)
				(type solid)
			)
			(layer "F.SilkS")
		)
		(fp_rect
			(start 1.25 0.65)
			(end -1.25 -0.65)
			(stroke
				(width 0.05)
				(type solid)
			)
			(fill no)
			(layer "F.CrtYd")
		)
		(fp_line
			(start 0.201 -0.202)
			(end -0.101 0)
			(stroke
				(width 0.15)
				(type solid)
			)
			(layer "F.Fab")
		)
		(fp_line
			(start -0.199 -0.202)
			(end -0.199 0.1)
			(stroke
				(width 0.15)
				(type solid)
			)
			(layer "F.Fab")
		)
		(fp_line
			(start 0.599 0)
			(end 0.201 0)
			(stroke
				(width 0.15)
				(type solid)
			)
			(layer "F.Fab")
		)
		(fp_line
			(start 0.201 0)
			(end 0.201 -0.202)
			(stroke
				(width 0.15)
				(type solid)
			)
			(layer "F.Fab")
		)
		(fp_line
			(start -0.101 0)
			(end 0.201 0.2)
			(stroke
				(width 0.15)
				(type solid)
			)
			(layer "F.Fab")
		)
		(fp_line
			(start -0.199 0)
			(end -0.597 0)
			(stroke
				(width 0.15)
				(type solid)
			)
			(layer "F.Fab")
		)
		(fp_line
			(start 0.201 0.2)
			(end 0.201 0)
			(stroke
				(width 0.15)
				(type solid)
			)
			(layer "F.Fab")
		)
		(fp_line
			(start -0.199 0.2)
			(end -0.199 0.1)
			(stroke
				(width 0.15)
				(type solid)
			)
			(layer "F.Fab")
		)
		(fp_rect
			(start 0.848 0.4)
			(end -0.85 -0.402)
			(stroke
				(width 0.15)
				(type solid)
			)
			(fill no)
			(layer "F.Fab")
		)
		(fp_text user "${REFERENCE}"
			(at -1.4224 5.999 90)
			(layer "F.Fab")
			(effects
				(font
					(size 0.7 0.7)
					(thickness 0.15)
				)
				(justify left bottom)
			)
		)
		(fp_text user "License: Apache-2.0"
			(at -1.4224 3.599 90)
			(layer "F.Fab")
			(effects
				(font
					(size 0.7 0.7)
					(thickness 0.15)
				)
				(justify left bottom)
			)
		)
		(fp_text user "Author: Antmicro"
			(at -1.4224 4.799 90)
			(layer "F.Fab")
			(effects
				(font
					(size 0.7 0.7)
					(thickness 0.15)
				)
				(justify left bottom)
			)
		)
		(pad "1" smd roundrect
			(at -0.7 0 270)
			(size 0.8 1)
			(layers "F.Cu" "F.Mask" "F.Paste")
			(roundrect_rratio 0.2)
			(net 151 "+3V3")
			(pinfunction "C")
			(pintype "passive")
		)
		(pad "2" smd roundrect
			(at 0.7 0 270)
			(size 0.8 1)
			(layers "F.Cu" "F.Mask" "F.Paste")
			(roundrect_rratio 0.2)
			(net 231 "Net-(D6-A)")
			(pinfunction "A")
			(pintype "passive")
		)
	)
)
